(kicad_pcb
	(version 20260206)
	(generator "pcbnew")
	(generator_version "10.0")
	(general
		(thickness 1.21888)
		(legacy_teardrops no)
	)
	(paper "A4")
	(title_block
		(title "timecard-proto-v0 — Timingcard_PCB.PcbDoc")
		(comment 1 "Time Appliance Project (Time Card) / footprints 32-43 of 167")
	)
	(layers
		(0 "F.Cu" signal "TOP")
		(4 "In1.Cu" signal "SGND")
		(6 "In2.Cu" signal "IN1")
		(8 "In3.Cu" signal "IN2")
		(10 "In4.Cu" signal "SGND1")
		(2 "B.Cu" signal "BOTTOM")
		(9 "F.Adhes" user "F.Adhesive")
		(11 "B.Adhes" user "B.Adhesive")
		(13 "F.Paste" user "Top Paste")
		(15 "B.Paste" user "Bottom Paste")
		(5 "F.SilkS" user "Top Overlay")
		(7 "B.SilkS" user "Bottom Overlay")
		(1 "F.Mask" user "Top Solder")
		(3 "B.Mask" user "Bottom Solder")
		(17 "Dwgs.User" user "User.Drawings")
		(19 "Cmts.User" user "User.Comments")
		(21 "Eco1.User" user "User.Eco1")
		(23 "Eco2.User" user "User.Eco2")
		(25 "Edge.Cuts" user)
		(27 "Margin" user)
		(31 "F.CrtYd" user "Top Courtyard")
		(29 "B.CrtYd" user "Bottom Courtyard")
		(35 "F.Fab" user "Top Component Center")
		(33 "B.Fab" user "Bottom Component Center")
	)
	(footprint "Miscellaneous:L101011MS02Q"
		(layer "F.Cu")
		(at 201.013595 62.9286 180)
		(property "Reference" "SW1"
			(at 5.57487 -11.713655 0)
			(unlocked yes)
			(layer "F.SilkS")
			(effects
				(font
					(size 0.762 0.762)
					(thickness 0.2286)
				)
				(justify left bottom)
			)
		)
		(property "Value" "L101011MS02Q"
			(at 5.6261 -12.41679 0)
			(unlocked yes)
			(layer "F.SilkS")
			(hide yes)
			(effects
				(font
					(size 1.524 1.524)
					(thickness 0.254)
				)
				(justify left bottom)
			)
		)
		(sheetname "POWER")
		(sheetfile "POWER.kicad_sch")
		(duplicate_pad_numbers_are_jumpers no)
		(fp_line
			(start 5.44828 9.652)
			(end -5.588 9.652)
			(stroke
				(width 0.1524)
				(type solid)
			)
			(layer "F.SilkS")
		)
		(fp_line
			(start 5.44828 3.50504)
			(end 5.44828 9.652)
			(stroke
				(width 0.1524)
				(type solid)
			)
			(layer "F.SilkS")
		)
		(fp_line
			(start 5.44828 -9.652)
			(end 5.44828 3.50504)
			(stroke
				(width 0.1524)
				(type solid)
			)
			(layer "F.SilkS")
		)
		(fp_line
			(start 5.44828 -9.652)
			(end -5.588 -9.652)
			(stroke
				(width 0.1524)
				(type solid)
			)
			(layer "F.SilkS")
		)
		(fp_line
			(start -5.588 -9.652)
			(end -5.588 9.652)
			(stroke
				(width 0.1524)
				(type solid)
			)
			(layer "F.SilkS")
		)
		(pad "1" thru_hole circle
			(at -2.85 4.6 180)
			(size 2.5 2.5)
			(drill 1.65)
			(layers "*.Cu" "*.Mask")
			(remove_unused_layers no)
			(net "NetD2_1")
			(thermal_bridge_angle 90)
		)
		(pad "2" thru_hole circle
			(at -2.85 0 180)
			(size 2.5 2.5)
			(drill 1.65)
			(layers "*.Cu" "*.Mask")
			(remove_unused_layers no)
			(net "NetD1_1")
			(thermal_bridge_angle 90)
		)
	)
	(footprint "Passives:SODFL370X135-2N"
		(layer "F.Cu")
		(at 217.869595 70.0006)
		(property "Reference" "D2"
			(at 3.512345 0.578 90)
			(unlocked yes)
			(layer "F.SilkS")
			(effects
				(font
					(size 0.762 0.762)
					(thickness 0.2286)
				)
				(justify left bottom)
			)
		)
		(property "Value" "DFLZ39-TP"
			(at -2.0955 3.62839 0)
			(unlocked yes)
			(layer "F.SilkS")
			(hide yes)
			(effects
				(font
					(size 1.524 1.524)
					(thickness 0.254)
				)
				(justify left bottom)
			)
		)
		(sheetname "POWER")
		(sheetfile "POWER.kicad_sch")
		(duplicate_pad_numbers_are_jumpers no)
		(fp_line
			(start -1.55 -0.95)
			(end 1.55 -0.95)
			(stroke
				(width 0.2)
				(type solid)
			)
			(layer "F.SilkS")
		)
		(fp_line
			(start -1.55 -0.825)
			(end -1.55 -0.95)
			(stroke
				(width 0.2)
				(type solid)
			)
			(layer "F.SilkS")
		)
		(fp_line
			(start -1.55 0.95)
			(end -1.55 0.825)
			(stroke
				(width 0.2)
				(type solid)
			)
			(layer "F.SilkS")
		)
		(fp_line
			(start -1.55 0.95)
			(end 1.55 0.95)
			(stroke
				(width 0.2)
				(type solid)
			)
			(layer "F.SilkS")
		)
		(fp_line
			(start 1.55 -0.825)
			(end 1.55 -0.95)
			(stroke
				(width 0.2)
				(type solid)
			)
			(layer "F.SilkS")
		)
		(fp_line
			(start 1.55 0.95)
			(end 1.55 0.825)
			(stroke
				(width 0.2)
				(type solid)
			)
			(layer "F.SilkS")
		)
		(fp_circle
			(center -2.05 -0.825)
			(end -2.05 -0.875)
			(stroke
				(width 0.1)
				(type solid)
			)
			(fill no)
			(layer "F.SilkS")
		)
		(pad "1" smd rect
			(at -1.825 0 90)
			(size 1.05 0.65)
			(layers "F.Cu" "F.Mask" "F.Paste")
			(net "NetD2_1")
		)
		(pad "2" smd rect
			(at 1.825 0 90)
			(size 1.05 0.65)
			(layers "F.Cu" "F.Mask" "F.Paste")
			(net "NetD2_2")
		)
	)
	(footprint "SamacSys:BMP388"
		(layer "F.Cu")
		(at 140.763595 89.0786)
		(property "Reference" "U4"
			(at -0.313405 -2.921949 0)
			(unlocked yes)
			(layer "F.SilkS")
			(effects
				(font
					(size 0.762 0.762)
					(thickness 0.254)
				)
			)
		)
		(property "Value" "BMP388"
			(at 3.364105 3.038602 0)
			(unlocked yes)
			(layer "F.SilkS")
			(hide yes)
			(effects
				(font
					(size 1.524 1.524)
					(thickness 0.254)
				)
			)
		)
		(sheetname "GPS_IMU_SENSORS")
		(sheetfile "GPS_IMU_SENSORS.kicad_sch")
		(duplicate_pad_numbers_are_jumpers no)
		(fp_line
			(start -1 -1)
			(end -0.5 -1)
			(stroke
				(width 0.1)
				(type solid)
			)
			(layer "F.SilkS")
		)
		(fp_line
			(start -1 -0.8)
			(end -1 -1)
			(stroke
				(width 0.1)
				(type solid)
			)
			(layer "F.SilkS")
		)
		(fp_line
			(start -1 1)
			(end -1 0.8)
			(stroke
				(width 0.1)
				(type solid)
			)
			(layer "F.SilkS")
		)
		(fp_line
			(start -1 1)
			(end -0.5 1)
			(stroke
				(width 0.1)
				(type solid)
			)
			(layer "F.SilkS")
		)
		(fp_line
			(start 0.5 -1)
			(end 1 -1)
			(stroke
				(width 0.1)
				(type solid)
			)
			(layer "F.SilkS")
		)
		(fp_line
			(start 0.5 1)
			(end 1 1)
			(stroke
				(width 0.1)
				(type solid)
			)
			(layer "F.SilkS")
		)
		(fp_line
			(start 1 -0.8)
			(end 1 -1)
			(stroke
				(width 0.1)
				(type solid)
			)
			(layer "F.SilkS")
		)
		(fp_line
			(start 1 1)
			(end 1 0.8)
			(stroke
				(width 0.1)
				(type solid)
			)
			(layer "F.SilkS")
		)
		(fp_arc
			(start 0.2 -1.3)
			(mid 0.25 -1.35)
			(end 0.3 -1.3)
			(stroke
				(width 0.1)
				(type solid)
			)
			(layer "F.SilkS")
		)
		(fp_arc
			(start 0.3 -1.3)
			(mid 0.25 -1.25)
			(end 0.2 -1.3)
			(stroke
				(width 0.1)
				(type solid)
			)
			(layer "F.SilkS")
		)
		(pad "1" smd rect
			(at 0.25 -0.763 90)
			(size 0.275 0.25)
			(layers "F.Cu" "F.Mask" "F.Paste")
			(net "+3.3V_CLEAN")
		)
		(pad "2" smd rect
			(at -0.25 -0.763 90)
			(size 0.275 0.25)
			(layers "F.Cu" "F.Mask" "F.Paste")
			(net "SCL")
		)
		(pad "3" smd rect
			(at -0.762 -0.5)
			(size 0.275 0.25)
			(layers "F.Cu" "F.Mask" "F.Paste")
			(net "GND")
		)
		(pad "4" smd rect
			(at -0.762 0)
			(size 0.275 0.25)
			(layers "F.Cu" "F.Mask" "F.Paste")
			(net "SDA")
		)
		(pad "5" smd rect
			(at -0.762 0.5)
			(size 0.275 0.25)
			(layers "F.Cu" "F.Mask" "F.Paste")
		)
		(pad "6" smd rect
			(at -0.25 0.763 90)
			(size 0.275 0.25)
			(layers "F.Cu" "F.Mask" "F.Paste")
			(net "+3.3V_CLEAN")
		)
		(pad "7" smd rect
			(at 0.25 0.763 90)
			(size 0.275 0.25)
			(layers "F.Cu" "F.Mask" "F.Paste")
		)
		(pad "8" smd rect
			(at 0.762 0.5)
			(size 0.275 0.25)
			(layers "F.Cu" "F.Mask" "F.Paste")
			(net "GND")
		)
		(pad "9" smd rect
			(at 0.762 0)
			(size 0.275 0.25)
			(layers "F.Cu" "F.Mask" "F.Paste")
			(net "GND")
		)
		(pad "10" smd rect
			(at 0.762 -0.5)
			(size 0.275 0.25)
			(layers "F.Cu" "F.Mask" "F.Paste")
			(net "+3.3V_CLEAN")
		)
	)
	(footprint "Resistors:RESC1608X50N"
		(layer "F.Cu")
		(at 107.608195 56.3862 -90)
		(property "Reference" "R43"
			(at -1.557775 0.96487 0)
			(unlocked yes)
			(layer "F.SilkS")
			(effects
				(font
					(size 0.762 0.762)
					(thickness 0.2286)
				)
				(justify left bottom)
			)
		)
		(property "Value" "ERJ-3EKF1002V"
			(at 3.72999 0.4445 0)
			(unlocked yes)
			(layer "F.SilkS")
			(hide yes)
			(effects
				(font
					(size 1.524 1.524)
					(thickness 0.254)
				)
				(justify left bottom)
			)
		)
		(sheetname "GPS_IMU_SENSORS")
		(sheetfile "GPS_IMU_SENSORS.kicad_sch")
		(duplicate_pad_numbers_are_jumpers no)
		(fp_line
			(start 0 0.5)
			(end 0 -0.5)
			(stroke
				(width 0.1524)
				(type solid)
			)
			(layer "F.SilkS")
		)
		(pad "1" smd rect
			(at -0.69 0)
			(size 1 0.72)
			(layers "F.Cu" "F.Mask" "F.Paste")
			(net "+5.0V")
		)
		(pad "2" smd rect
			(at 0.69 0)
			(size 1 0.72)
			(layers "F.Cu" "F.Mask" "F.Paste")
			(net "NetR43_2")
		)
	)
	(footprint "Miscellaneous Devices:J1-0603"
		(layer "F.Cu")
		(at 92.688595 58.7786 90)
		(property "Reference" "R11"
			(at 0.375005 -1.270584 90)
			(unlocked yes)
			(layer "F.SilkS")
			(effects
				(font
					(face "Arial")
					(size 0.48006 0.48006)
					(thickness 0.254)
				)
			)
		)
		(property "Value" "MACTX"
			(at 0.164598 3.46595 0)
			(unlocked yes)
			(layer "F.SilkS")
			(hide yes)
			(effects
				(font
					(size 1.524 1.524)
					(thickness 0.254)
				)
			)
		)
		(sheetname "GPS_IMU_SENSORS")
		(sheetfile "GPS_IMU_SENSORS.kicad_sch")
		(duplicate_pad_numbers_are_jumpers no)
		(fp_line
			(start -0.2 -0.35)
			(end 0.2 -0.35)
			(stroke
				(width 0.2)
				(type solid)
			)
			(layer "F.SilkS")
		)
		(fp_line
			(start -0.2 0.35)
			(end 0.2 0.35)
			(stroke
				(width 0.2)
				(type solid)
			)
			(layer "F.SilkS")
		)
		(pad "1" smd rect
			(at -0.75 0 180)
			(size 0.9 0.7)
			(layers "F.Cu" "F.Mask" "F.Paste")
			(net "MAC_TX")
		)
		(pad "2" smd rect
			(at 0.75 0 180)
			(size 0.9 0.7)
			(layers "F.Cu" "F.Mask" "F.Paste")
			(net "NetJP1_3")
		)
	)
	(footprint "Capacitors:CAPC2012X14N"
		(layer "F.Cu")
		(at 205.213595 75.2036 180)
		(property "Reference" "C1"
			(at 0.81255 -3.026855 0)
			(unlocked yes)
			(layer "F.SilkS")
			(effects
				(font
					(size 0.762 0.762)
					(thickness 0.2286)
				)
				(justify left bottom)
			)
		)
		(property "Value" "CAP_0805_10UF_25V"
			(at 1.5875 -3.52679 0)
			(unlocked yes)
			(layer "F.SilkS")
			(hide yes)
			(effects
				(font
					(size 1.524 1.524)
					(thickness 0.254)
				)
				(justify left bottom)
			)
		)
		(sheetname "POWER")
		(sheetfile "POWER.kicad_sch")
		(duplicate_pad_numbers_are_jumpers no)
		(fp_line
			(start 0.762 0.9652)
			(end -0.762 0.9652)
			(stroke
				(width 0.1524)
				(type solid)
			)
			(layer "F.SilkS")
		)
		(fp_line
			(start 0.762 -0.9652)
			(end -0.762 -0.9652)
			(stroke
				(width 0.1524)
				(type solid)
			)
			(layer "F.SilkS")
		)
		(pad "1" smd rect
			(at -0.9 0 270)
			(size 1.45 1.15)
			(layers "F.Cu" "F.Mask" "F.Paste")
			(net "+12V")
		)
		(pad "2" smd rect
			(at 0.9 0 270)
			(size 1.45 1.15)
			(layers "F.Cu" "F.Mask" "F.Paste")
			(net "GND")
		)
	)
	(footprint "Vault:RESC1608X50X30NL20T20"
		(layer "F.Cu")
		(at 152.083595 64.4126 180)
		(property "Reference" "R26"
			(at 1.195 -2.459345 0)
			(unlocked yes)
			(layer "F.SilkS")
			(effects
				(font
					(size 0.762 0.762)
					(thickness 0.2286)
				)
				(justify left bottom)
			)
		)
		(property "Value" "499 OHM"
			(at 0.2413 -3.42519 0)
			(unlocked yes)
			(layer "F.SilkS")
			(hide yes)
			(effects
				(font
					(size 1.524 1.524)
					(thickness 0.254)
				)
				(justify left bottom)
			)
		)
		(sheetname "UART")
		(sheetfile "UART.kicad_sch")
		(duplicate_pad_numbers_are_jumpers no)
		(pad "1" smd rect
			(at -0.65 0 270)
			(size 1 0.9)
			(layers "F.Cu" "F.Mask" "F.Paste")
			(net "UART1_TXD")
		)
		(pad "2" smd rect
			(at 0.65 0 270)
			(size 1 0.9)
			(layers "F.Cu" "F.Mask" "F.Paste")
			(net "NetD10_1")
		)
	)
	(footprint "IntegratedCircuits:SOIC127P600X175-8N"
		(layer "F.Cu")
		(at 217.361595 101.7506 180)
		(property "Reference" "U2"
			(at 6.13379 -2.264855 0)
			(unlocked yes)
			(layer "F.SilkS")
			(effects
				(font
					(size 0.762 0.762)
					(thickness 0.2286)
				)
				(justify left bottom)
			)
		)
		(property "Value" "MP1482DS-LF"
			(at -12.7381 8.69061 0)
			(unlocked yes)
			(layer "F.SilkS")
			(hide yes)
			(effects
				(font
					(size 1.524 1.524)
					(thickness 0.254)
				)
				(justify left bottom)
			)
		)
		(sheetname "POWER")
		(sheetfile "POWER.kicad_sch")
		(duplicate_pad_numbers_are_jumpers no)
		(fp_line
			(start 2 2.5)
			(end -2 2.5)
			(stroke
				(width 0.12)
				(type solid)
			)
			(layer "F.SilkS")
		)
		(fp_line
			(start 2 -2.5)
			(end -3.4 -2.5)
			(stroke
				(width 0.12)
				(type solid)
			)
			(layer "F.SilkS")
		)
		(pad "1" smd rect
			(at -2.475 -1.905 180)
			(size 1.97 0.57)
			(layers "F.Cu" "F.Mask" "F.Paste")
			(net "NetC3_1")
		)
		(pad "2" smd rect
			(at -2.475 -0.635 180)
			(size 1.97 0.57)
			(layers "F.Cu" "F.Mask" "F.Paste")
			(net "+12V")
		)
		(pad "3" smd rect
			(at -2.475 0.635 180)
			(size 1.97 0.57)
			(layers "F.Cu" "F.Mask" "F.Paste")
			(net "NetC3_2")
		)
		(pad "4" smd rect
			(at -2.475 1.905 180)
			(size 1.97 0.57)
			(layers "F.Cu" "F.Mask" "F.Paste")
			(net "GND")
		)
		(pad "5" smd rect
			(at 2.475 1.905 180)
			(size 1.97 0.57)
			(layers "F.Cu" "F.Mask" "F.Paste")
			(net "NetR5_1")
		)
		(pad "6" smd rect
			(at 2.475 0.635 180)
			(size 1.97 0.57)
			(layers "F.Cu" "F.Mask" "F.Paste")
			(net "NetC22_2")
		)
		(pad "7" smd rect
			(at 2.475 -0.635 180)
			(size 1.97 0.57)
			(layers "F.Cu" "F.Mask" "F.Paste")
			(net "NetR3_1")
		)
		(pad "8" smd rect
			(at 2.475 -1.905 180)
			(size 1.97 0.57)
			(layers "F.Cu" "F.Mask" "F.Paste")
			(net "NetC21_2")
		)
	)
	(footprint "Capacitors:CAPC2012X14N"
		(layer "F.Cu")
		(at 125.540595 69.8736 -90)
		(property "Reference" "C60"
			(at 4.805 -2.641345 90)
			(unlocked yes)
			(layer "F.SilkS")
			(effects
				(font
					(size 0.762 0.762)
					(thickness 0.2286)
				)
				(justify left bottom)
			)
		)
		(property "Value" "CAP_0805_10UF_25V"
			(at 3.52679 1.5875 0)
			(unlocked yes)
			(layer "F.SilkS")
			(hide yes)
			(effects
				(font
					(size 1.524 1.524)
					(thickness 0.254)
				)
				(justify left bottom)
			)
		)
		(sheetname "GPS_IMU_SENSORS")
		(sheetfile "GPS_IMU_SENSORS.kicad_sch")
		(duplicate_pad_numbers_are_jumpers no)
		(fp_line
			(start 0.762 0.9652)
			(end -0.762 0.9652)
			(stroke
				(width 0.1524)
				(type solid)
			)
			(layer "F.SilkS")
		)
		(fp_line
			(start 0.762 -0.9652)
			(end -0.762 -0.9652)
			(stroke
				(width 0.1524)
				(type solid)
			)
			(layer "F.SilkS")
		)
		(pad "1" smd rect
			(at -0.9 0)
			(size 1.45 1.15)
			(layers "F.Cu" "F.Mask" "F.Paste")
			(net "+5.0V")
		)
		(pad "2" smd rect
			(at 0.9 0)
			(size 1.45 1.15)
			(layers "F.Cu" "F.Mask" "F.Paste")
			(net "GND")
		)
	)
	(footprint "Vault:CAPC1608X90X35NL10T15"
		(layer "F.Cu")
		(at 212.535595 100.6076 90)
		(property "Reference" "C22"
			(at 1.479 0.396345 90)
			(unlocked yes)
			(layer "F.SilkS")
			(effects
				(font
					(size 0.762 0.762)
					(thickness 0.2286)
				)
				(justify left bottom)
			)
		)
		(property "Value" "0.033uF"
			(at 8.20801 25.6159 0)
			(unlocked yes)
			(layer "F.SilkS")
			(hide yes)
			(effects
				(font
					(size 1.524 1.524)
					(thickness 0.254)
				)
				(justify left bottom)
			)
		)
		(sheetname "POWER")
		(sheetfile "POWER.kicad_sch")
		(duplicate_pad_numbers_are_jumpers no)
		(pad "1" smd rect
			(at -0.675 0 180)
			(size 0.95 0.85)
			(layers "F.Cu" "F.Mask" "F.Paste")
			(net "NetC22_1")
		)
		(pad "2" smd rect
			(at 0.675 0 180)
			(size 0.95 0.85)
			(layers "F.Cu" "F.Mask" "F.Paste")
			(net "NetC22_2")
		)
	)
	(footprint "Passives:INDC1608X09N"
		(layer "F.Cu")
		(at 171.133595 89.0506 90)
		(property "Reference" "FB2"
			(at 0.45769 2.417265 90)
			(unlocked yes)
			(layer "F.SilkS")
			(effects
				(font
					(size 0.762 0.762)
					(thickness 0.2286)
				)
				(justify left bottom)
			)
		)
		(property "Value" "MPZ1608_220OHM_0603"
			(at -3.88239 -0.5461 0)
			(unlocked yes)
			(layer "F.SilkS")
			(hide yes)
			(effects
				(font
					(size 1.524 1.524)
					(thickness 0.254)
				)
				(justify left bottom)
			)
		)
		(sheetname "MAC")
		(sheetfile "MAC.kicad_sch")
		(duplicate_pad_numbers_are_jumpers no)
		(pad "1" smd rect
			(at -0.665 0 180)
			(size 0.98 0.87)
			(layers "F.Cu" "F.Mask" "F.Paste")
			(net "+3.3V")
		)
		(pad "2" smd rect
			(at 0.665 0 180)
			(size 0.98 0.87)
			(layers "F.Cu" "F.Mask" "F.Paste")
			(net "NetC72_2")
		)
	)
	(footprint "Passives:DIOM1608X06N"
		(layer "F.Cu")
		(at 167.813595 69.0536)
		(property "Reference" "D4"
			(at 2.175 0.418345 0)
			(unlocked yes)
			(layer "F.SilkS")
			(effects
				(font
					(size 0.762 0.762)
					(thickness 0.2286)
				)
				(justify left bottom)
			)
		)
		(property "Value" "RED"
			(at -1.4097 3.22199 0)
			(unlocked yes)
			(layer "F.SilkS")
			(hide yes)
			(effects
				(font
					(size 1.524 1.524)
					(thickness 0.254)
				)
				(justify left bottom)
			)
		)
		(sheetname "POWER")
		(sheetfile "POWER.kicad_sch")
		(duplicate_pad_numbers_are_jumpers no)
		(fp_circle
			(center -1.275 -0.725)
			(end -1.275 -0.775)
			(stroke
				(width 0.1)
				(type solid)
			)
			(fill no)
			(layer "F.SilkS")
		)
		(pad "1" smd rect
			(at -0.725 0 90)
			(size 0.85 1)
			(layers "F.Cu" "F.Mask" "F.Paste")
			(net "NetD4_1")
		)
		(pad "2" smd rect
			(at 0.725 0 90)
			(size 0.85 1)
			(layers "F.Cu" "F.Mask" "F.Paste")
			(net "+3.3V")
		)
	)
)
